FILE_TYPE = MULTI_PHYS_TABLE;

PART 'K4A8G165WCBCTD'

{========================================================================================}
:VALUE             | PART_TYPE | MATERIAL | PART_NUMBER    = STANDARD | LIFECYCLE      | PART_NUMBER   | JEDEC_TYPE | DESCRIPTION                               | MANUFTR | MANUF_PN          | RD_CMPLS_LVL | CMPLS_LVL | FROM_PJ           | CLASS | DIP_SMD | DATA                      | EE_CHECK_LIST | FP_ECN | PSL | CREATOR | STATUS | MSD   | ESD_CDM | ESD_HBM | ESD_MM | PIN_LENGTH_SHORT_PIN | PIN_LENGTH_LONG_PIN | CREATEDAY  ;
{========================================================================================}
 'K4A8G165WC-BCTD' | 'SMLF'    | 'IC'     | 'AKD5FGUT502'(!) = ''       | ''               | 'AKD5FGUT502' |'BGA96XB'| 'IC SDRAM(96P)K4A8G165WC-BCTD(FBGA)QBCON' | 'SAM'   | 'K4A8G165WC-BCTD' | 'EP(V1)'     | 'CG'      | 'STORM PEAK-ERIC' | 'IC'  | ''      | 'SAM_K4A8G165WC-BCTD.pdf' | ''            | ''     | ''  | ''      | ''     | 'N/A' | 'N/A'   | 'N/A'   | 'N/A'  | '0 MILS'             | '0 MILS'            | '20180814'
 'K4A8G165WC-BCTD' | 'SMLF'    | 'EMPTY'  | 'AKD5FGUT502'(!) = ''       | ''               | 'AKD5FGUT502' |'BGA96XB'| 'IC SDRAM(96P)K4A8G165WC-BCTD(FBGA)QBCON' | 'SAM'   | 'K4A8G165WC-BCTD' | 'EP(V1)'     | 'CG'      | 'STORM PEAK-ERIC' | 'IC'  | ''      | 'SAM_K4A8G165WC-BCTD.pdf' | ''            | ''     | ''  | ''      | ''     | 'N/A' | 'N/A'   | 'N/A'   | 'N/A'  | '0 MILS'             | '0 MILS'            | '20180814'

END_PART

END.

